# T6G (Grand Teton) — schematic parts with pin connectivity, parts 6377–6523 of 8303; source: Cadence DE-HDL packaged netlist (pstxprt.dat, pstxnet.dat, pstchip.dat)

R1738  Q_RES  0 5% CHIP  pkg 0402LF  page 171 : 1 = JTAG_SCM_MUX_R_TDI ; 2 = JTAG_SCM_MUX_TDI
R1739  Q_RES  0 5% CHIP  pkg 0402LF  page 171 : 1 = JTAG_SCM_MUX_R_TDO ; 2 = JTAG_SCM_MUX_TDO
R1740  Q_RES  22 1% CHIP  pkg 0402LF  page 171 : 1 = JTAG_SCM_PLD_R_TCK ; 2 = JTAG_SCM_PLD_TCK
R1741  Q_RES  22 1% CHIP  pkg 0402LF  page 171 : 1 = JTAG_SCM_PLD_R_TMS ; 2 = JTAG_SCM_PLD_TMS
R1742  Q_RES  22 1% CHIP  pkg 0402LF  page 171 : 1 = JTAG_SCM_PLD_R_TDI ; 2 = JTAG_SCM_PLD_TDI
R1743  Q_RES  22 1% CHIP  pkg 0402LF  page 171 : 1 = JTAG_SCM_PLD_R_TDO ; 2 = JTAG_SCM_PLD_TDO
R1744  Q_RES  10K 1% CHIP  pkg 0402LF  page 171 : 1 = P3V3_AUX ; 2 = JTAG_SCM_MUX_TDI
R1745  Q_RES  10K 1% CHIP  pkg 0402LF  page 171 : 1 = P3V3_AUX ; 2 = JTAG_SCM_MUX_TDO
R1746  Q_RES  10K 1% CHIP  pkg 0402LF  page 171 : 1 = P3V3_AUX ; 2 = JTAG_SCM_MUX_TMS
R1747  Q_RES  10K 1% CHIP  pkg 0402LF  page 171 : 1 = P3V3_AUX ; 2 = JTAG_SCM_MUX_TCK
R1748  Q_RES  10K 1% EMPTY  pkg 0402LF  page 171 : 1 = JTAG_SCM_MUX_TCK ; 2 = GND
R1775  Q_RES  1K 1% CHIP  pkg 0402LF  page 187 : 1 = P3V_BAT ; 2 = P3V_BAT_R
R1776  Q_RES  1K 1% CHIP  pkg 0402LF  page 187 : 1 = CLR_CMOS ; 2 = GND
R1777  Q_RES  1K 1% CHIP  pkg 0402LF  page 187 : 1 = P1V5_BAT_IN ; 2 = BAT_LDO_EN
R1779  Q_RES  100 1% CHIP  pkg 0402LF  page 187 : 1 = CLR_CMOS_N ; 2 = P1V5_BAT
R1785  Q_RES  4.7K 1% CHIP  pkg 0402LF  page 257 : 1 = P3V3_AUX_ADC ; 2 = GND
R1791  Q_RES  9.09K 1% CHIP  pkg 0402LF  page 257 : 1 = P5V_ADC ; 2 = GND
R1792  Q_RES  0 5% EMPTY  pkg 0402LF  page 257 : 1 = SMB_SCM_2_R4_SDA ; 2 = SMB_SEN_MAM_3V3AUX_SDA
R1793  Q_RES  0 5% EMPTY  pkg 0402LF  page 257 : 1 = SMB_SCM_2_R4_SCL ; 2 = SMB_SEN_MAM_3V3AUX_SCL
R1798  Q_RES  0 5% CHIP  pkg 0402LF  page 150 : 1 = SCM_ROT_CPU_RST_R_N ; 2 = SCM_ROT_CPU_RST_N
R1799  Q_RES  7.87K 1% CHIP  pkg 0402LF  page 257 : 1 = P12V_AUX ; 2 = P12V_AUX_ADC
R1800  Q_RES  1.21K 1% CHIP  pkg 0402LF  page 257 : 1 = P12V_AUX_ADC ; 2 = GND
R1801  Q_RES  0 5% CHIP  pkg 0402LF  page 150 : 1 = PRSNT0_N ; 2 = GND
R1815  Q_RES  0 5% CHIP  pkg 0402LF  page 150 : 1 = SCM_SYS_PWRBTN_N ; 2 = SCM_SYS_PWRBTN_R_N
R1816  Q_RES  0 5% CHIP  pkg 0402LF  page 150 : 1 = PWRGD_PS_PWROK ; 2 = PWRGD_PS_PWROK_R
R1822  Q_RES  10K 1% CHIP  pkg 0402LF  page 250 : 1 = P3V3_AUX ; 2 = RST_SMB_SWITCH_N
R1824  Q_RES  10K 1% CHIP  pkg 0402LF  page 133 : 1 = P3V3_OCP_SFF ; 2 = IRQ_LVC3_OCP_SFF_WAKE_N

R1837  Q_RES_4P_12  0.001 1% CHIP  pkg R2512_4P_H41  page 259
  1  \1\  UNSPEC  = P12V_AUX
  2  \2\  UNSPEC  = P12V_MEM_CPU1
  3  \3\  UNSPEC  = TP_P12V_AUX_CPU1_DIMM_ISEN_P
  4  \4\  UNSPEC  = TP_P12V_AUX_CPU1_DIMM_ISEN_N

R1838  Q_RES_4P_12  0.001 1% CHIP  pkg R2512_4P_H41  page 259
  1  \1\  UNSPEC  = P12V_AUX
  2  \2\  UNSPEC  = P12V_MEM_CPU0
  3  \3\  UNSPEC  = TP_P12V_AUX_CPU0_DIMM_ISEN_P
  4  \4\  UNSPEC  = TP_P12V_AUX_CPU0_DIMM_ISEN_N

R1854  Q_RES  1K 1% CHIP  pkg 0402LF  page 152 : 1 = P3V3_AUX ; 2 = FM_SCM_PRSNT1_N
R1856  Q_RES  100 1% CHIP  pkg 0402LF  page 152 : 1 = FM_SCM_PRSNT1_N ; 2 = FM_SCM_PRSNT1_R_N
R1857  Q_RES  10K 1% CHIP  pkg 0402LF  page 152 : 1 = P3V3_AUX ; 2 = P12V_SCM_EN
R1895  Q_RES  0 5% CHIP  pkg 0402LF  page 131 : 1 = OCP_SFF_PRSNTA_R_N ; 2 = GND
R1896  Q_RES  100 1% CHIP  pkg 0402LF  page 132 : 1 = OCP_SFF_ISO_BIF0_EN ; 2 = GND
R1897  Q_RES  100 1% CHIP  pkg 0402LF  page 132 : 1 = OCP_SFF_ISO_BIF1_EN ; 2 = GND
R1898  Q_RES  100 1% CHIP  pkg 0402LF  page 132 : 1 = OCP_SFF_ISO_BIF2_EN ; 2 = GND
R1905  Q_RES  1K 1% CHIP  pkg 0402LF  page 134 : 1 = P3V3_AUX ; 2 = OCP_SFF_PRSNT0_R_N
R1906  Q_RES  1K 1% CHIP  pkg 0402LF  page 134 : 1 = P3V3_AUX ; 2 = OCP_SFF_PRSNT2_R_N
R1907  Q_RES  1K 1% CHIP  pkg 0402LF  page 134 : 1 = P3V3_AUX ; 2 = OCP_SFF_PRSNT1_R_N
R1908  Q_RES  1K 1% CHIP  pkg 0402LF  page 134 : 1 = P3V3_AUX ; 2 = OCP_SFF_PRSNT3_R_N
R1929  Q_RES  10K 1% CHIP  pkg 0402LF  page 131 : 1 = GND ; 2 = OCP_SFF_AUX_PWR_EN
R1930  Q_RES  10K 1% CHIP  pkg 0402LF  page 131 : 1 = GND ; 2 = OCP_SFF_MAIN_PWR_EN
R2113  Q_RES  0 5% CHIP  pkg 0402LF  page 144 : 1 = RST_PERST_BUF_M2_0_N ; 2 = RST_PERST_BUF_M2_0_R_N
R2114  Q_RES  0 5% CHIP  pkg 0402LF  page 145 : 1 = SMB_PCIE_E1S_ISO_EN_R2 ; 2 = SMB_PCIE_E1S_ISO_EN
R2121  Q_RES  4.7K 5% CHIP  pkg 0402LF  page 144 : 1 = P3V3_AUX ; 2 = RST_PERST_BUF_M2_0_N
R2125  Q_RES  4.7K 5% CHIP  pkg 0402LF  page 145 : 1 = P3V3_AUX ; 2 = SMB_PCIE_E1S_ISO_EN
R2204  Q_RES  2.2K 5% EMPTY  pkg 0402LF  page 250 : 1 = P3V3_AUX ; 2 = SMB_PCIE0_3V3AUX_SCL
R2205  Q_RES  2.2K 5% EMPTY  pkg 0402LF  page 250 : 1 = P3V3_AUX ; 2 = SMB_PCIE0_3V3AUX_SDA
R2212  Q_RES  2.2K 5% EMPTY  pkg 0402LF  page 151 : 1 = SMB_HOST_CLK_3V3AUX_SCL ; 2 = P3V3_AUX
R2213  Q_RES  2.2K 5% EMPTY  pkg 0402LF  page 151 : 1 = SMB_HOST_CLK_3V3AUX_SDA ; 2 = P3V3_AUX
R2219  Q_RES  267K 1% EMPTY  pkg 0402LF  page 268 : 1 = P12V_AUX ; 2 = A_P12V_STBY_ADR_TRIGGER
R2221  Q_RES  26.7K 1% EMPTY  pkg 0402LF  page 268 : 1 = P12V_AUX ; 2 = A_P12V_STBY_FP_TRIGGER
R2222  Q_RES  1K 1% EMPTY  pkg 0402LF  page 268 : 1 = A_P12V_STBY_FP_TRIGGER ; 2 = GND
R2227  Q_RES  10K 1% EMPTY  pkg 0402LF  page 268 : 1 = A_P12V_STBY_ADR_TRIGGER ; 2 = GND
R2230  Q_RES  10K 1% EMPTY  pkg 0402LF  page 268 : 1 = P3V3_AUX ; 2 = A_P12V_STBY_FPH_GATE
R2233  Q_RES  1K 1% EMPTY  pkg 0402LF  page 268 : 1 = P3V3_AUX ; 2 = FM_UV_ADR_TRIGGER_N
R2261  Q_RES  33.2 1% CHIP  pkg 0402LF  page 81 : 1 = FM_SWB_PWR_EN_R ; 2 = FM_SWB_PWR_EN
R2262  Q_RES  33.2 1% CHIP  pkg 0402LF  page 81 : 1 = FM_GPU_PWR_EN_R ; 2 = FM_GPU_PWR_EN
R2268  Q_RES  0 5% CHIP  pkg 0402LF  page 250 : 1 = RST_SMB_SWITCH_N ; 2 = PU_RST_SMB_PCIE0_N
R2310  Q_RES  0 5% EMPTY  pkg 0402LF  page 159 : 1 = I3C_0_SPD_DDRAF_CPU0_R_SCL ; 2 = I3C_SPD_DDRAF_CPU0_BYPASS_SCL
R2311  Q_RES  0 5% EMPTY  pkg 0402LF  page 159 : 1 = I3C_0_SPD_DDRAF_CPU0_R_SDA ; 2 = I3C_SPD_DDRAF_CPU0_BYPASS_SDA
R2316  Q_RES  0 5% CHIP  pkg 0402LF  page 189 : 1 = PWRGD_P5V_AUX_R ; 2 = PWRGD_P5V_AUX
R2317  Q_RES  10K 1% CHIP  pkg 0402LF  page 145 : 1 = P3V3_E1S_0 ; 2 = PU_E1S_0_DUALPORT_EN_N
R2318  Q_RES  0 5% CHIP  pkg 0402LF  page 27 : 1 = UART_CPU0_SCM_UART1_R_TX ; 2 = UART_CPU0_SCM_UART1_TX
R2343  Q_RES  10K 1% EMPTY  pkg 0402LF  page 85 : 1 = P5V_AUX_VCC ; 2 = PWRGD_P5V_AUX
R2344  Q_RES  4.7K 5% CHIP  pkg 0402LF  page 85 : 1 = P3V3_AUX ; 2 = PWRGD_P5V_AUX_R1
R2346  Q_RES  100K 1% CHIP  pkg 0402LF  page 85 : 1 = P3V3_AUX ; 2 = PWRGD_P5V_AUX_R2
R2356  Q_RES  10K 1% CHIP  pkg 0402LF  page 189 : 1 = P5V_AUX_VCC ; 2 = PWRGD_P5V_AUX_R
R2410  Q_RES  33.2 1% CHIP  pkg 0402LF  page 148 : 1 = SMB_M2_P1_1V8AUX_SDA_R ; 2 = SMB_M2_P1_1V8AUX_SDA
R2411  Q_RES  33.2 1% CHIP  pkg 0402LF  page 148 : 1 = SMB_M2_P1_1V8AUX_SCL_R ; 2 = SMB_M2_P1_1V8AUX_SCL
R2413  Q_RES  33.2 1% CHIP  pkg 0402LF  page 150 : 1 = SMB_2_BMC_GPU_SCL ; 2 = SMB_PCIE2_3V3AUX_SCL_R0
R2414  Q_RES  33.2 1% CHIP  pkg 0402LF  page 150 : 1 = SMB_2_BMC_GPU_SDA ; 2 = SMB_PCIE2_3V3AUX_SDA_R0
R2415  Q_RES  33.2 1% CHIP  pkg 0402LF  page 150 : 1 = SMB_1_BMC_GPU_SCL ; 2 = SMB_PCIE3_3V3AUX_SCL_R
R2416  Q_RES  33.2 1% CHIP  pkg 0402LF  page 150 : 1 = SMB_1_BMC_GPU_SDA ; 2 = SMB_PCIE3_3V3AUX_SDA_R
R2417  Q_RES  33.2 1% CHIP  pkg 0402LF  page 150 : 1 = SMB_HOST_CLK_3V3AUX_SCL ; 2 = SMB_HOST_CLK_3V3AUX_SCL_R0
R2418  Q_RES  33.2 1% CHIP  pkg 0402LF  page 150 : 1 = SMB_HOST_CLK_3V3AUX_SDA ; 2 = SMB_HOST_CLK_3V3AUX_SDA_R0
R2419  Q_RES  33.2 1% CHIP  pkg 0402LF  page 150 : 1 = SMB_CPU0_CPU1_APML_SCL ; 2 = SMB_CPU0_CPU1_APML_SCL_R
R2420  Q_RES  33.2 1% CHIP  pkg 0402LF  page 150 : 1 = SMB_CPU0_CPU1_APML_SDA ; 2 = SMB_CPU0_CPU1_APML_SDA_R
R2421  Q_RES  33.2 1% CHIP  pkg 0402LF  page 150 : 1 = SMB_VR_SENSOR_3V3AUX_SCL ; 2 = SMB_VR_3V3AUX_SCL_R0
R2422  Q_RES  33.2 1% CHIP  pkg 0402LF  page 150 : 1 = SMB_VR_SENSOR_3V3AUX_SDA ; 2 = SMB_VR_3V3AUX_SDA_R0
R2423  Q_RES  33.2 1% CHIP  pkg 0402LF  page 150 : 1 = SMB_PMBUS_3V3AUX_SCL ; 2 = SMB_PMBUS_3V3AUX_SCL_R0
R2424  Q_RES  33.2 1% CHIP  pkg 0402LF  page 150 : 1 = SMB_PMBUS_3V3AUX_SDA ; 2 = SMB_PMBUS_3V3AUX_SDA_R0
R2425  Q_RES  33.2 1% CHIP  pkg 0402LF  page 150 : 1 = SMB_OCP_V3_2_3V3AUX_SCL ; 2 = SMB_OCP_V3_2_3V3AUX_SCL_R0
R2426  Q_RES  100 1% EMPTY  pkg 0402LF  page 145 : 1 = E1S_0_PERST1_CLKREQ_N ; 2 = GND
R2473  Q_RES  0 5% CHIP  pkg 0402LF  page 132 : 1 = FB_BMC_ISOLATE_R1 ; 2 = FB_BMC_ISOLATE
R2474  Q_RES  0 5% EMPTY  pkg 0402LF  page 132 : 1 = FM_NCSI_OCP_SFF_R_OE ; 2 = FB_BMC_ISOLATE
R2476  Q_RES  200K 1% EMPTY  pkg 0402LF  page 148 : 1 = SMB_PCIE_M2_0_EN ; 2 = PWRGD_P1V8_AUX_R
R2487  Q_RES  4.7K 1% EMPTY  pkg 0402LF  page 133 : 1 = P3V3_AUX ; 2 = IRQ_LVC3_WAKE_BUF_N
R2488  Q_RES  4.7K 1% CHIP  pkg 0402LF  page 133 : 1 = P3V3_AUX ; 2 = OCP_SFF_WAKE_BUFF_N
R2489  Q_RES  33.2 1% CHIP  pkg 0402LF  page 133 : 1 = IRQ_LVC3_WAKE_BUF_N ; 2 = IRQ_OCP_SFF_WAKE_BUF_N
R2528  Q_RES  100K 1% CHIP  pkg 0402LF  page 242 : 1 = P12V_AUX ; 2 = FM_P12V_HSC_EN_N
R2529  Q_RES  0 5% CHIP  pkg 0402LF  page 242 : 1 = FM_P12V_HSC_EN_N ; 2 = FM_P12V_HSC_EN_R_N
R2530  Q_RES  4.7K 5% CHIP  pkg 0402LF  page 242 : 1 = P12V_AUX ; 2 = P12V_AUX_BLEEDING
R2531  Q_RES  0 5% CHIP  pkg 0402LF  page 242 : 1 = MB0_P12V_STBY_PWRGD ; 2 = FM_P12V_HSC_EN_R
R2565  Q_RES  0 5% CHIP  pkg 0402LF  page 250 : 1 = SMB_FRU_3V3AUX_SCL_R ; 2 = SMB_FRU_3V3AUX_SCL
R2566  Q_RES  0 5% CHIP  pkg 0402LF  page 250 : 1 = SMB_FRU_3V3AUX_SDA_R ; 2 = SMB_FRU_3V3AUX_SDA
R2585  Q_RES  31.6K 1% CHIP  pkg 0402LF  page 268 : 1 = HSC_EN ; 2 = GND
R2586  Q_RES  0 5% CHIP  pkg 0402LF  page 262 : 1 = HSC_EN ; 2 = HSC_EN_R
R2587  Q_RES  1K 1% CHIP  pkg 0402LF  page 262 : 1 = IRQ_HSC_FAULT_N ; 2 = HSC_VDD
R2588  Q_RES  22 1% CHIP  pkg 0402LF  page 262 : 1 = HSC_FAULT ; 2 = IRQ_HSC_FAULT_N
R2624  Q_RES  49.9 1% CHIP  pkg 0402LF  page 267 : 1 = P12V_HSC_TEMP_E ; 2 = P12V_HSC_TEMP_D-
R2625  Q_RES  49.9 1% CHIP  pkg 0402LF  page 267 : 1 = P12V_HSC_TEMP_R ; 2 = P12V_HSC_TEMP_D+
R2626  Q_RES  0 5% CHIP  pkg 0402LF  page 267 : 1 = SMB_P12V_HSC_TEMP_SCL ; 2 = SMB_P12V_HSC_SCL
R2627  Q_RES  0 5% CHIP  pkg 0402LF  page 267 : 1 = SMB_P12V_HSC_TEMP_SDA ; 2 = SMB_P12V_HSC_SDA
R2628  Q_RES  0 5% CHIP  pkg 0402LF  page 267 : 1 = P12V_HSC_TEMP_ALERT_N ; 2 = P12V_HSC_TEMP_ALERT_R_N
R2656  Q_RES  100 1% EMPTY  pkg 0402LF  page 123 : 1 = HGX_DETECT_N_ISO ; 2 = GND
R2659  Q_RES  0 5% CHIP  pkg 0402LF  page 28 : 1 = CLK_100M_CPU0_CLK11_R_DP ; 2 = CLK_100M_CPU0_CLK11_DP
R2660  Q_RES  0 5% CHIP  pkg 0402LF  page 28 : 1 = CLK_100M_CPU0_CLK11_R_DN ; 2 = CLK_100M_CPU0_CLK11_DN
R2663  Q_RES  33.2 1% CHIP  pkg 0402LF  page 81 : 1 = FM_SWB_PWRGD_ISO_R ; 2 = FM_SWB_PWRGD_ISO
R2664  Q_RES  33.2 1% CHIP  pkg 0402LF  page 81 : 1 = FM_GPU_PWRGD_ISO_R ; 2 = FM_GPU_PWRGD_ISO
R2666  Q_RES  10K 1% CHIP  pkg 0402LF  page 248 : 1 = SMB_BMC_SWB_EN ; 2 = GND
R2667  Q_RES  2.2K 5% CHIP  pkg 0402LF  page 248 : 1 = P3V3_AUX ; 2 = SMB_BMC_SWB_BUF_R_SCL
R2668  Q_RES  4.7K 5% EMPTY  pkg 0402LF  page 248 : 1 = P3V3_AUX ; 2 = I3C_BMC_SWB_BUF_R_SDA
R2669  Q_RES  2.2K 5% CHIP  pkg 0402LF  page 248 : 1 = P3V3_AUX ; 2 = SMB_BMC_SWB_BUF_R_SDA
R2670  Q_RES  4.7K 5% EMPTY  pkg 0402LF  page 248 : 1 = P3V3_AUX ; 2 = I3C_BMC_SWB_BUF_R_SCL
R2671  Q_RES  33.2 1% CHIP  pkg 0402LF  page 248 : 1 = SMB_BMC_SWB_BUF_R_SCL ; 2 = SMB_BMC_SWB_BUF_SCL
R2672  Q_RES  33.2 1% CHIP  pkg 0402LF  page 248 : 1 = SMB_BMC_SWB_BUF_R_SDA ; 2 = SMB_BMC_SWB_BUF_SDA
R2674  Q_RES  27 5% CHIP  pkg 0402LF  page 248 : 1 = I3C_BMC_SWB_BUF_R_SDA ; 2 = I3C_BMC_SWB_BUF_SDA
R2675  Q_RES  33.2 1% CHIP  pkg 0402LF  page 248 : 1 = I3C_BMC_SWB_BUF_R_SCL ; 2 = I3C_BMC_SWB_BUF_SCL
R2676  Q_RES  0 5% CHIP  pkg 0402LF  page 248 : 1 = SMB_BMC_SWB_EN ; 2 = SMB_BMC_SWB_EN_R2
R2693  Q_RES  1K 1% EMPTY  pkg 0402LF  page 245 : 1 = P3V3_AUX ; 2 = TCA9539_0_ADD1
R2694  Q_RES  1K 1% CHIP  pkg 0402LF  page 245 : 1 = TCA9539_0_ADD1 ; 2 = GND
R2695  Q_RES  1K 1% EMPTY  pkg 0402LF  page 245 : 1 = P3V3_AUX ; 2 = TCA9539_0_ADD0
R2696  Q_RES  1K 1% CHIP  pkg 0402LF  page 245 : 1 = TCA9539_0_ADD0 ; 2 = GND
R2703  Q_RES  0 5% CHIP  pkg 0402LF  page 250 : 1 = SMB_BMC_SWB_SCL_R4 ; 2 = SMB_BMC_SWB_SCL
R2704  Q_RES  0 5% CHIP  pkg 0402LF  page 250 : 1 = SMB_BMC_SWB_SDA_R4 ; 2 = SMB_BMC_SWB_SDA
R2705  Q_RES  0 5% EMPTY  pkg 0402LF  page 248 : 1 = SMB_BMC_SWB_R_SCL ; 2 = SMB_BMC_SWB_BUF_R_SCL
R2706  Q_RES  0 5% CHIP  pkg 0402LF  page 248 : 1 = I3C_BMC_SWB_R_SDA ; 2 = I3C_BMC_SWB_BUF_R_SDA
R2707  Q_RES  0 5% CHIP  pkg 0402LF  page 248 : 1 = SMB_BMC_SWB_EN ; 2 = SMB_BMC_SWB_EN_R
R2724  Q_RES  0 5% EMPTY  pkg 0402LF  page 248 : 1 = SMB_BMC_SWB_R_SDA ; 2 = SMB_BMC_SWB_BUF_R_SDA
R2725  Q_RES  0 5% CHIP  pkg 0402LF  page 248 : 1 = I3C_BMC_SWB_R_SCL ; 2 = I3C_BMC_SWB_BUF_R_SCL
R2786  Q_RES  0 5% CHIP  pkg 0402LF  page 234 : 1 = USB2_HUB_SWB_DP ; 2 = USB2_HUB_BUF_SWB_R_DP
R2787  Q_RES  0 5% CHIP  pkg 0402LF  page 234 : 1 = USB2_HUB_SWB_DN ; 2 = USB2_HUB_BUF_SWB_R_DN
R2788  Q_RES  0 5% EMPTY  pkg 0402LF  page 234 : 1 = USB2_HOST_BMC_B_BUF_DP ; 2 = USB2_HUB_BUF_SWB_R_DP
R2789  Q_RES  0 5% EMPTY  pkg 0402LF  page 234 : 1 = USB2_HOST_BMC_B_BUF_DN ; 2 = USB2_HUB_BUF_SWB_R_DN
R2790  Q_RES  0 5% EMPTY  pkg 0402LF  page 234 : 1 = USB2_HOST_BMC_B_DP ; 2 = USB2_HOST_BMC_B_BUF_DP
R2791  Q_RES  0 5% EMPTY  pkg 0402LF  page 234 : 1 = USB2_HOST_BMC_B_DN ; 2 = USB2_HOST_BMC_B_BUF_DN
R2793  Q_RES  0 5% CHIP  pkg 0402LF  page 240 : 1 = FM_PDB_BUF_EN_R_N ; 2 = FM_PDB_BUF_EN_R1_N
R2794  Q_RES  4.7K 5% CHIP  pkg 0402LF  page 240 : 1 = P3V3_AUX ; 2 = FM_PDB_BUF_EN_R1
R2796  Q_RES  0 5% CHIP  pkg 0402LF  page 240 : 1 = FM_PDB_BUF_EN_R1 ; 2 = MB_PDB_SMB9_R_EN
R2800  Q_RES  0 5% EMPTY  pkg 0402LF  page 240 : 1 = SMB_FAN_3V3AUX_R_SCL ; 2 = SMB_FAN_3V3AUX_BUF_SCL
R2801  Q_RES  0 5% EMPTY  pkg 0402LF  page 240 : 1 = SMB_FAN_3V3AUX_R_SDA ; 2 = SMB_FAN_3V3AUX_BUF_SDA
R2802  Q_RES  0 5% CHIP  pkg 0402LF  page 240 : 1 = HPDB_HSC_PWRGD_R ; 2 = HPDB_HSC_PWRGD
R2803  Q_RES  0 5% CHIP  pkg 0402LF  page 240 : 1 = FM_FAN_PWR_EN_R ; 2 = FM_FAN_PWR_EN
R2805  Q_RES  4.7K 5% EMPTY  pkg 0402LF  page 240 : 1 = P3V3_AUX ; 2 = SMB_FAN_3V3AUX_BUF_SCL
R2807  Q_RES  4.7K 5% EMPTY  pkg 0402LF  page 240 : 1 = P3V3_AUX ; 2 = SMB_FAN_3V3AUX_BUF_SDA
R2811  Q_RES  33.2 1% CHIP  pkg 0402LF  page 240 : 1 = SMB_FAN_3V3AUX_BUF_SCL ; 2 = SMB_FAN_3V3AUX_BUF_R_SCL
